(kicad_pcb
	(version 20241229)
	(generator "pcbnew")
	(generator_version "9.0")
	(general
		(thickness 1.294)
		(legacy_teardrops no)
	)
	(paper "A3")
	(title_block
		(title "Kintex 410T devboard")
		(date "2024-04-03")
		(rev "1.1.2")
		(comment 9 "footprints 257-262 of 975")
	)
	(layers
		(0 "F.Cu" mixed)
		(4 "In1.Cu" power)
		(6 "In2.Cu" power)
		(8 "In3.Cu" mixed)
		(10 "In4.Cu" power)
		(12 "In5.Cu" mixed)
		(14 "In6.Cu" power)
		(16 "In7.Cu" mixed)
		(18 "In8.Cu" power)
		(2 "B.Cu" mixed)
		(9 "F.Adhes" user "F.Adhesive")
		(11 "B.Adhes" user "B.Adhesive")
		(13 "F.Paste" user)
		(15 "B.Paste" user)
		(5 "F.SilkS" user "F.Silkscreen")
		(7 "B.SilkS" user "B.Silkscreen")
		(1 "F.Mask" user)
		(3 "B.Mask" user)
		(17 "Dwgs.User" user "User.Drawings")
		(19 "Cmts.User" user "User.Comments")
		(21 "Eco1.User" user "User.Eco1")
		(23 "Eco2.User" user "User.Eco2")
		(25 "Edge.Cuts" user)
		(27 "Margin" user)
		(31 "F.CrtYd" user "F.Courtyard")
		(29 "B.CrtYd" user "B.Courtyard")
		(35 "F.Fab" user)
		(33 "B.Fab" user)
	)
	(footprint "antmicro-footprints:R_0402_1005Metric"
		(layer "F.Cu")
		(at 235.915 122.5 180)
		(descr "Resistor SMD 0402")
		(tags "resistor SMD 0402")
		(property "Reference" "R76"
			(at -0.735 -0.35 180)
			(layer "F.SilkS")
			(effects
				(font
					(size 0.7 0.7)
					(thickness 0.15)
				)
				(justify left bottom)
			)
		)
		(property "Value" "R_0R_0402"
			(at 0 1.4 180)
			(layer "F.Fab")
			(effects
				(font
					(size 0.7 0.7)
					(thickness 0.15)
				)
				(justify left bottom)
			)
		)
		(property "Description" "SMD Chip Resistor, Jumper, 0 ohm, 100 mW, 0402 [1005 Metric], Thick Film, General Purpose"
			(at 0 0 180)
			(layer "F.Fab")
			(hide yes)
			(effects
				(font
					(size 1.27 1.27)
					(thickness 0.15)
				)
			)
		)
		(property "Author" "Antmicro"
			(at 471.83 245 0)
			(layer "F.Fab")
			(hide yes)
			(effects
				(font
					(size 1 1)
					(thickness 0.15)
				)
			)
		)
		(property "Current" "1A"
			(at 471.83 245 0)
			(layer "F.Fab")
			(hide yes)
			(effects
				(font
					(size 1 1)
					(thickness 0.15)
				)
			)
		)
		(property "License" "Apache-2.0"
			(at 471.83 245 0)
			(layer "F.Fab")
			(hide yes)
			(effects
				(font
					(size 1 1)
					(thickness 0.15)
				)
			)
		)
		(property "MPN" "ERJ2GE0R00X"
			(at 471.83 245 0)
			(layer "F.Fab")
			(hide yes)
			(effects
				(font
					(size 1 1)
					(thickness 0.15)
				)
			)
		)
		(property "Manufacturer" "Panasonic"
			(at 471.83 245 0)
			(layer "F.Fab")
			(hide yes)
			(effects
				(font
					(size 1 1)
					(thickness 0.15)
				)
			)
		)
		(property "Tolerance" ""
			(at 471.83 245 0)
			(layer "F.Fab")
			(hide yes)
			(effects
				(font
					(size 1 1)
					(thickness 0.15)
				)
			)
		)
		(property "Val" "0R"
			(at 471.83 245 0)
			(layer "F.Fab")
			(hide yes)
			(effects
				(font
					(size 1 1)
					(thickness 0.15)
				)
			)
		)
		(sheetname "SPI Flash + SD Card")
		(sheetfile "spi-flash.kicad_sch")
		(attr smd)
		(fp_rect
			(start -0.925 -0.47)
			(end 0.925 0.47)
			(stroke
				(width 0.05)
				(type default)
			)
			(fill no)
			(layer "F.CrtYd")
		)
		(fp_rect
			(start -0.5 -0.25)
			(end 0.5 0.25)
			(stroke
				(width 0.15)
				(type solid)
			)
			(fill no)
			(layer "F.Fab")
		)
		(pad "1" smd roundrect
			(at -0.48 0 180)
			(size 0.59 0.64)
			(layers "F.Cu" "F.Mask" "F.Paste")
			(roundrect_rratio 0.25)
			(net 38 "/FPGA Bank 14 & 15/SYSTEM_FLASH.DQ0")
			(pintype "passive")
		)
		(pad "2" smd roundrect
			(at 0.48 0 180)
			(size 0.59 0.64)
			(layers "F.Cu" "F.Mask" "F.Paste")
			(roundrect_rratio 0.25)
			(net 896 "/SPI Flash + SD Card/SYSTEM_FLASH_DQ0")
			(pintype "passive")
		)
	)
	(footprint "antmicro-footprints:R_0402_1005Metric"
		(layer "F.Cu")
		(at 235.9 112.6 180)
		(descr "Resistor SMD 0402")
		(tags "resistor SMD 0402")
		(property "Reference" "R96"
			(at -0.8 -0.375 180)
			(layer "F.SilkS")
			(effects
				(font
					(size 0.7 0.7)
					(thickness 0.15)
				)
				(justify left bottom)
			)
		)
		(property "Value" "R_100R_0402"
			(at 0 1.4 180)
			(layer "F.Fab")
			(effects
				(font
					(size 0.7 0.7)
					(thickness 0.15)
				)
				(justify left bottom)
			)
		)
		(property "Description" "SMD Chip Resistor, 100 ohm, ± 1%, 62.5 mW, 0402 [1005 Metric], Thick Film, General Purpose"
			(at 0 0 180)
			(layer "F.Fab")
			(hide yes)
			(effects
				(font
					(size 1.27 1.27)
					(thickness 0.15)
				)
			)
		)
		(property "Author" "Antmicro"
			(at 471.8 225.2 0)
			(layer "F.Fab")
			(hide yes)
			(effects
				(font
					(size 1 1)
					(thickness 0.15)
				)
			)
		)
		(property "DNP" "DNP"
			(at 471.8 225.2 0)
			(layer "F.Fab")
			(hide yes)
			(effects
				(font
					(size 1 1)
					(thickness 0.15)
				)
			)
		)
		(property "License" "Apache-2.0"
			(at 471.8 225.2 0)
			(layer "F.Fab")
			(hide yes)
			(effects
				(font
					(size 1 1)
					(thickness 0.15)
				)
			)
		)
		(property "MPN" "CR0402-FX-1000GLF"
			(at 471.8 225.2 0)
			(layer "F.Fab")
			(hide yes)
			(effects
				(font
					(size 1 1)
					(thickness 0.15)
				)
			)
		)
		(property "Manufacturer" "Bourns"
			(at 471.8 225.2 0)
			(layer "F.Fab")
			(hide yes)
			(effects
				(font
					(size 1 1)
					(thickness 0.15)
				)
			)
		)
		(property "Tolerance" "1%"
			(at 471.8 225.2 0)
			(layer "F.Fab")
			(hide yes)
			(effects
				(font
					(size 1 1)
					(thickness 0.15)
				)
			)
		)
		(property "Val" "100R"
			(at 471.8 225.2 0)
			(layer "F.Fab")
			(hide yes)
			(effects
				(font
					(size 1 1)
					(thickness 0.15)
				)
			)
		)
		(property "dnp" ""
			(at 471.8 225.2 0)
			(layer "F.Fab")
			(hide yes)
			(effects
				(font
					(size 1 1)
					(thickness 0.15)
				)
			)
		)
		(property "exclude_from_bom" ""
			(at 471.8 225.2 0)
			(layer "F.Fab")
			(hide yes)
			(effects
				(font
					(size 1 1)
					(thickness 0.15)
				)
			)
		)
		(sheetname "SPI Flash + SD Card")
		(sheetfile "spi-flash.kicad_sch")
		(attr smd exclude_from_bom)
		(fp_rect
			(start -0.925 -0.47)
			(end 0.925 0.47)
			(stroke
				(width 0.05)
				(type default)
			)
			(fill no)
			(layer "F.CrtYd")
		)
		(fp_rect
			(start -0.5 -0.25)
			(end 0.5 0.25)
			(stroke
				(width 0.15)
				(type solid)
			)
			(fill no)
			(layer "F.Fab")
		)
		(pad "1" smd roundrect
			(at -0.48 0 180)
			(size 0.59 0.64)
			(layers "F.Cu" "F.Mask" "F.Paste")
			(roundrect_rratio 0.25)
			(net 427 "/FPGA Bank 16 & 17/USR_FLASH_1.CLK")
			(pintype "passive")
		)
		(pad "2" smd roundrect
			(at 0.48 0 180)
			(size 0.59 0.64)
			(layers "F.Cu" "F.Mask" "F.Paste")
			(roundrect_rratio 0.25)
			(net 3 "VCC_USR_B")
			(pintype "passive")
		)
	)
	(footprint "antmicro-footprints:R_0402_1005Metric"
		(layer "F.Cu")
		(at 236 139 180)
		(descr "Resistor SMD 0402")
		(tags "resistor SMD 0402")
		(property "Reference" "R188"
			(at 1.9 -2.35 180)
			(layer "F.SilkS")
			(effects
				(font
					(size 0.7 0.7)
					(thickness 0.15)
				)
				(justify left bottom)
			)
		)
		(property "Value" "R_0R_0402"
			(at 0 1.4 180)
			(layer "F.Fab")
			(effects
				(font
					(size 0.7 0.7)
					(thickness 0.15)
				)
				(justify left bottom)
			)
		)
		(property "Description" "SMD Chip Resistor, Jumper, 0 ohm, 100 mW, 0402 [1005 Metric], Thick Film, General Purpose"
			(at 0 0 180)
			(layer "F.Fab")
			(hide yes)
			(effects
				(font
					(size 1.27 1.27)
					(thickness 0.15)
				)
			)
		)
		(property "Author" "Antmicro"
			(at 472 278 0)
			(layer "F.Fab")
			(hide yes)
			(effects
				(font
					(size 1 1)
					(thickness 0.15)
				)
			)
		)
		(property "Current" "1A"
			(at 472 278 0)
			(layer "F.Fab")
			(hide yes)
			(effects
				(font
					(size 1 1)
					(thickness 0.15)
				)
			)
		)
		(property "License" "Apache-2.0"
			(at 472 278 0)
			(layer "F.Fab")
			(hide yes)
			(effects
				(font
					(size 1 1)
					(thickness 0.15)
				)
			)
		)
		(property "MPN" "ERJ2GE0R00X"
			(at 472 278 0)
			(layer "F.Fab")
			(hide yes)
			(effects
				(font
					(size 1 1)
					(thickness 0.15)
				)
			)
		)
		(property "Manufacturer" "Panasonic"
			(at 472 278 0)
			(layer "F.Fab")
			(hide yes)
			(effects
				(font
					(size 1 1)
					(thickness 0.15)
				)
			)
		)
		(property "Tolerance" ""
			(at 472 278 0)
			(layer "F.Fab")
			(hide yes)
			(effects
				(font
					(size 1 1)
					(thickness 0.15)
				)
			)
		)
		(property "Val" "0R"
			(at 472 278 0)
			(layer "F.Fab")
			(hide yes)
			(effects
				(font
					(size 1 1)
					(thickness 0.15)
				)
			)
		)
		(sheetname "USB PHY")
		(sheetfile "usb-phy.kicad_sch")
		(attr smd)
		(fp_rect
			(start -0.925 -0.47)
			(end 0.925 0.47)
			(stroke
				(width 0.05)
				(type default)
			)
			(fill no)
			(layer "F.CrtYd")
		)
		(fp_rect
			(start -0.5 -0.25)
			(end 0.5 0.25)
			(stroke
				(width 0.15)
				(type solid)
			)
			(fill no)
			(layer "F.Fab")
		)
		(pad "1" smd roundrect
			(at -0.48 0 180)
			(size 0.59 0.64)
			(layers "F.Cu" "F.Mask" "F.Paste")
			(roundrect_rratio 0.25)
			(net 941 "/USB PHY/FTDI_SCL")
			(pintype "passive")
		)
		(pad "2" smd roundrect
			(at 0.48 0 180)
			(size 0.59 0.64)
			(layers "F.Cu" "F.Mask" "F.Paste")
			(roundrect_rratio 0.25)
			(net 1338 "/I2C.SCL")
			(pintype "passive")
		)
	)
	(footprint "antmicro-footprints:R_0402_1005Metric"
		(layer "F.Cu")
		(at 261.7 130.7)
		(descr "Resistor SMD 0402")
		(tags "resistor SMD 0402")
		(property "Reference" "R190"
			(at -1.4 1.55 180)
			(layer "F.SilkS")
			(effects
				(font
					(size 0.7 0.7)
					(thickness 0.15)
				)
				(justify left bottom)
			)
		)
		(property "Value" "R_10k_0402"
			(at 0 1.4 0)
			(layer "F.Fab")
			(effects
				(font
					(size 0.7 0.7)
					(thickness 0.15)
				)
				(justify left bottom)
			)
		)
		(property "Description" "SMD Chip Resistor, 10 kohm, ± 1%, 62.5 mW, 0402 [1005 Metric], Thick Film, General Purpose"
			(at 0 0 0)
			(layer "F.Fab")
			(hide yes)
			(effects
				(font
					(size 1.27 1.27)
					(thickness 0.15)
				)
			)
		)
		(property "Author" "Antmicro"
			(at 0 0 0)
			(layer "F.Fab")
			(hide yes)
			(effects
				(font
					(size 1 1)
					(thickness 0.15)
				)
			)
		)
		(property "License" "Apache-2.0"
			(at 0 0 0)
			(layer "F.Fab")
			(hide yes)
			(effects
				(font
					(size 1 1)
					(thickness 0.15)
				)
			)
		)
		(property "MPN" "CR0402-FX-1002GLF"
			(at 0 0 0)
			(layer "F.Fab")
			(hide yes)
			(effects
				(font
					(size 1 1)
					(thickness 0.15)
				)
			)
		)
		(property "Manufacturer" "Bourns"
			(at 0 0 0)
			(layer "F.Fab")
			(hide yes)
			(effects
				(font
					(size 1 1)
					(thickness 0.15)
				)
			)
		)
		(property "Tolerance" "1%"
			(at 0 0 0)
			(layer "F.Fab")
			(hide yes)
			(effects
				(font
					(size 1 1)
					(thickness 0.15)
				)
			)
		)
		(property "Val" "10k"
			(at 0 0 0)
			(layer "F.Fab")
			(hide yes)
			(effects
				(font
					(size 1 1)
					(thickness 0.15)
				)
			)
		)
		(sheetname "USB PHY")
		(sheetfile "usb-phy.kicad_sch")
		(attr smd)
		(fp_rect
			(start -0.925 -0.47)
			(end 0.925 0.47)
			(stroke
				(width 0.05)
				(type default)
			)
			(fill no)
			(layer "F.CrtYd")
		)
		(fp_rect
			(start -0.5 -0.25)
			(end 0.5 0.25)
			(stroke
				(width 0.15)
				(type solid)
			)
			(fill no)
			(layer "F.Fab")
		)
		(pad "1" smd roundrect
			(at -0.48 0)
			(size 0.59 0.64)
			(layers "F.Cu" "F.Mask" "F.Paste")
			(roundrect_rratio 0.25)
			(net 497 "/FPGA Bank 12 & 13/USB_USER.VDET")
			(pintype "passive")
		)
		(pad "2" smd roundrect
			(at 0.48 0)
			(size 0.59 0.64)
			(layers "F.Cu" "F.Mask" "F.Paste")
			(roundrect_rratio 0.25)
			(net 715 "/USB PHY/USB_USR_VBUS")
			(pintype "passive")
		)
	)
	(footprint "antmicro-footprints:LED_0603_1608Metric_G"
		(layer "F.Cu")
		(at 261.5 93.4)
		(descr "LED SMD 0603 Green")
		(tags "LED SMD 0603 Green")
		(property "Reference" "D22"
			(at -1 1.55 0)
			(layer "F.SilkS")
			(effects
				(font
					(size 0.7 0.7)
					(thickness 0.15)
				)
				(justify left bottom)
			)
		)
		(property "Value" "LED_G_0603_KP-1608CGCK"
			(at 0 1.6 0)
			(layer "F.Fab")
			(effects
				(font
					(size 0.7 0.7)
					(thickness 0.15)
				)
				(justify left bottom)
			)
		)
		(property "Description" "LED, Green, SMD, 0603, 20 mA, 2.1 V, 570 nm"
			(at 0 0 0)
			(layer "F.Fab")
			(hide yes)
			(effects
				(font
					(size 1.27 1.27)
					(thickness 0.15)
				)
			)
		)
		(property "Author" "Antmicro"
			(at 0 0 0)
			(layer "F.Fab")
			(hide yes)
			(effects
				(font
					(size 1 1)
					(thickness 0.15)
				)
			)
		)
		(property "Color" "Green"
			(at 0 0 0)
			(layer "F.Fab")
			(hide yes)
			(effects
				(font
					(size 1 1)
					(thickness 0.15)
				)
			)
		)
		(property "License" "Apache-2.0"
			(at 0 0 0)
			(layer "F.Fab")
			(hide yes)
			(effects
				(font
					(size 1 1)
					(thickness 0.15)
				)
			)
		)
		(property "MPN" "KP-1608CGCK"
			(at 0 0 0)
			(layer "F.Fab")
			(hide yes)
			(effects
				(font
					(size 1 1)
					(thickness 0.15)
				)
			)
		)
		(property "Manufacturer" "Kingbright"
			(at 0 0 0)
			(layer "F.Fab")
			(hide yes)
			(effects
				(font
					(size 1 1)
					(thickness 0.15)
				)
			)
		)
		(sheetname "User GPIO + LED + button + DIP switch")
		(sheetfile "user-gpio.kicad_sch")
		(attr smd)
		(fp_line
			(start -1.18 -0.319)
			(end -1.18 0.321)
			(stroke
				(width 0.15)
				(type solid)
			)
			(layer "F.SilkS")
		)
		(fp_line
			(start -0.094672 0.001008)
			(end -0.24 0.001008)
			(stroke
				(width 0.1)
				(type solid)
			)
			(layer "F.SilkS")
		)
		(fp_line
			(start -0.094672 0.001008)
			(end 0.105328 -0.198992)
			(stroke
				(width 0.1)
				(type solid)
			)
			(layer "F.SilkS")
		)
		(fp_line
			(start -0.094672 0.201008)
			(end -0.094672 -0.198992)
			(stroke
				(width 0.1)
				(type solid)
			)
			(layer "F.SilkS")
		)
		(fp_line
			(start 0.105328 0.001008)
			(end 0.24 0.001)
			(stroke
				(width 0.1)
				(type solid)
			)
			(layer "F.SilkS")
		)
		(fp_line
			(start 0.105328 0.201008)
			(end -0.094672 0.001008)
			(stroke
				(width 0.1)
				(type solid)
			)
			(layer "F.SilkS")
		)
		(fp_line
			(start 0.105328 0.201008)
			(end 0.105328 -0.198992)
			(stroke
				(width 0.1)
				(type solid)
			)
			(layer "F.SilkS")
		)
		(fp_line
			(start 0.22 -0.35)
			(end -0.22 -0.35)
			(stroke
				(width 0.15)
				(type solid)
			)
			(layer "F.SilkS")
		)
		(fp_line
			(start 0.22 0.35)
			(end -0.22 0.35)
			(stroke
				(width 0.15)
				(type solid)
			)
			(layer "F.SilkS")
		)
		(fp_rect
			(start 1.25 0.65)
			(end -1.25 -0.65)
			(stroke
				(width 0.05)
				(type solid)
			)
			(fill no)
			(layer "F.CrtYd")
		)
		(fp_line
			(start -0.199 -0.202)
			(end -0.199 0.1)
			(stroke
				(width 0.15)
				(type solid)
			)
			(layer "F.Fab")
		)
		(fp_line
			(start -0.199 0)
			(end -0.597 0)
			(stroke
				(width 0.15)
				(type solid)
			)
			(layer "F.Fab")
		)
		(fp_line
			(start -0.199 0.2)
			(end -0.199 0.1)
			(stroke
				(width 0.15)
				(type solid)
			)
			(layer "F.Fab")
		)
		(fp_line
			(start -0.101 0)
			(end 0.201 0.2)
			(stroke
				(width 0.15)
				(type solid)
			)
			(layer "F.Fab")
		)
		(fp_line
			(start 0.201 -0.202)
			(end -0.101 0)
			(stroke
				(width 0.15)
				(type solid)
			)
			(layer "F.Fab")
		)
		(fp_line
			(start 0.201 0)
			(end 0.201 -0.202)
			(stroke
				(width 0.15)
				(type solid)
			)
			(layer "F.Fab")
		)
		(fp_line
			(start 0.201 0.2)
			(end 0.201 0)
			(stroke
				(width 0.15)
				(type solid)
			)
			(layer "F.Fab")
		)
		(fp_line
			(start 0.599 0)
			(end 0.201 0)
			(stroke
				(width 0.15)
				(type solid)
			)
			(layer "F.Fab")
		)
		(fp_rect
			(start 0.848 0.4)
			(end -0.85 -0.402)
			(stroke
				(width 0.15)
				(type solid)
			)
			(fill no)
			(layer "F.Fab")
		)
		(pad "1" smd roundrect
			(at -0.7 0 180)
			(size 0.8 1)
			(layers "F.Cu" "F.Mask" "F.Paste")
			(roundrect_rratio 0.2)
			(net 27 "Net-(D22-C)")
			(pinfunction "C")
			(pintype "passive")
		)
		(pad "2" smd roundrect
			(at 0.7 0 180)
			(size 0.8 1)
			(layers "F.Cu" "F.Mask" "F.Paste")
			(roundrect_rratio 0.2)
			(net 783 "Net-(D22-A)")
			(pinfunction "A")
			(pintype "passive")
		)
	)
	(footprint "antmicro-footprints:C_0402_1005Metric"
		(layer "F.Cu")
		(at 199.253752 99.3615 90)
		(descr "Capacitor SMD 0402")
		(tags "capacitor SMD 0402")
		(property "Reference" "C290"
			(at -9.3385 5.546248 90)
			(layer "F.SilkS")
			(effects
				(font
					(size 0.7 0.7)
					(thickness 0.15)
				)
				(justify left bottom)
			)
		)
		(property "Value" "C_100n_0402"
			(at 0 1.169 90)
			(layer "F.Fab")
			(effects
				(font
					(size 0.7 0.7)
					(thickness 0.15)
				)
				(justify left bottom)
			)
		)
		(property "Description" "SMD Multilayer Ceramic Capacitor, 0.1 µF, 50 V, 0402 [1005 Metric], ± 10%, X5R, GRM Series"
			(at 0 0 90)
			(layer "F.Fab")
			(hide yes)
			(effects
				(font
					(size 1.27 1.27)
					(thickness 0.15)
				)
			)
		)
		(property "Author" "Antmicro"
			(at 298.615252 -99.892252 0)
			(layer "F.Fab")
			(hide yes)
			(effects
				(font
					(size 1 1)
					(thickness 0.15)
				)
			)
		)
		(property "Dielectric" "X5R"
			(at 298.615252 -99.892252 0)
			(layer "F.Fab")
			(hide yes)
			(effects
				(font
					(size 1 1)
					(thickness 0.15)
				)
			)
		)
		(property "License" "Apache-2.0"
			(at 298.615252 -99.892252 0)
			(layer "F.Fab")
			(hide yes)
			(effects
				(font
					(size 1 1)
					(thickness 0.15)
				)
			)
		)
		(property "MPN" "GRM155R61H104KE14D"
			(at 298.615252 -99.892252 0)
			(layer "F.Fab")
			(hide yes)
			(effects
				(font
					(size 1 1)
					(thickness 0.15)
				)
			)
		)
		(property "Manufacturer" "Murata"
			(at 298.615252 -99.892252 0)
			(layer "F.Fab")
			(hide yes)
			(effects
				(font
					(size 1 1)
					(thickness 0.15)
				)
			)
		)
		(property "Val" "100n"
			(at 298.615252 -99.892252 0)
			(layer "F.Fab")
			(hide yes)
			(effects
				(font
					(size 1 1)
					(thickness 0.15)
				)
			)
		)
		(property "Voltage" "50V"
			(at 298.615252 -99.892252 0)
			(layer "F.Fab")
			(hide yes)
			(effects
				(font
					(size 1 1)
					(thickness 0.15)
				)
			)
		)
		(sheetname "HDMI + Ethernet")
		(sheetfile "hdmi-ethernet.kicad_sch")
		(attr smd)
		(fp_rect
			(start -0.925 -0.47)
			(end 0.925 0.47)
			(stroke
				(width 0.05)
				(type default)
			)
			(fill no)
			(layer "F.CrtYd")
		)
		(fp_line
			(start 0.504 -0.25)
			(end 0.504 0.248)
			(stroke
				(width 0.15)
				(type solid)
			)
			(layer "F.Fab")
		)
		(fp_line
			(start -0.494 -0.25)
			(end 0.504 -0.25)
			(stroke
				(width 0.15)
				(type solid)
			)
			(layer "F.Fab")
		)
		(fp_line
			(start 0.504 0.248)
			(end -0.494 0.248)
			(stroke
				(width 0.15)
				(type solid)
			)
			(layer "F.Fab")
		)
		(fp_line
			(start -0.494 0.248)
			(end -0.494 -0.25)
			(stroke
				(width 0.15)
				(type solid)
			)
			(layer "F.Fab")
		)
		(pad "1" smd roundrect
			(at -0.48 0 90)
			(size 0.59 0.64)
			(layers "F.Cu" "F.Mask" "F.Paste")
			(roundrect_rratio 0.25)
			(net 1 "GND")
			(pintype "passive")
		)
		(pad "2" smd roundrect
			(at 0.48 0 90)
			(size 0.59 0.64)
			(layers "F.Cu" "F.Mask" "F.Paste")
			(roundrect_rratio 0.25)
			(net 727 "+1V2")
			(pintype "passive")
		)
	)
)
